# T6G (Grand Teton) — schematic netlist excerpt (pin names and nets, part order shuffled) for the footprints in the layout excerpt that follows; sources: Cadence DE-HDL packaged netlist, KiCad conversion of 04192023_DAF0TMB3IC0_F0TG_MB_C_brd_V02_OCP.brd

R1095  Q_RES  0 5% CHIP  pkg 0603LF  page 312 : A = P0V9_CPU0_RT3_2A_2D ; B = P0V9_CPU0_RT3_2A
C1087  Q_CAP  0.1UF 25V 10% X7R  pkg 0402  page 258 : A = P1V8_CPU0_RT_1D_ADC_TIC ; B = GND

(kicad_pcb
	(version 20260206)
	(generator "pcbnew")
	(generator_version "10.0")
	(general
		(thickness 1.6)
		(legacy_teardrops no)
	)
	(paper "A4")
	(title_block
		(title "04192023_DAF0TMB3IC0_F0TG_MB_C_brd_V02_OCP.brd")
		(comment 1 "Grand Teton / footprints 6831-6832 of 8354")
	)
	(layers
		(0 "F.Cu" signal "TOP")
		(4 "In1.Cu" signal "GND")
		(6 "In2.Cu" signal "IN1")
		(8 "In3.Cu" signal "GND1")
		(10 "In4.Cu" signal "IN2")
		(12 "In5.Cu" signal "GND2")
		(14 "In6.Cu" signal "IN3")
		(16 "In7.Cu" signal "GND3")
		(18 "In8.Cu" signal "VCC")
		(20 "In9.Cu" signal "VCC1")
		(22 "In10.Cu" signal "GND4")
		(24 "In11.Cu" signal "IN4")
		(26 "In12.Cu" signal "GND5")
		(28 "In13.Cu" signal "IN5")
		(30 "In14.Cu" signal "GND6")
		(32 "In15.Cu" signal "IN6")
		(34 "In16.Cu" signal "GND7")
		(2 "B.Cu" signal "BOTTOM")
		(9 "F.Adhes" user "F.Adhesive")
		(11 "B.Adhes" user "B.Adhesive")
		(13 "F.Paste" user "Package Geometry/Pastemask Top")
		(15 "B.Paste" user "Package Geometry/Pastemask Bottom")
		(5 "F.SilkS" user "Ref Des/Silkscreen Top")
		(7 "B.SilkS" user "Ref Des/Silkscreen Bottom")
		(1 "F.Mask" user "Board Geometry/Soldermask Top")
		(3 "B.Mask" user "Board Geometry/Soldermask Bottom")
		(17 "Dwgs.User" user "User.Drawings")
		(19 "Cmts.User" user "User.Comments")
		(21 "Eco1.User" user "User.Eco1")
		(23 "Eco2.User" user "User.Eco2")
		(25 "Edge.Cuts" user "Board Geometry/Outline")
		(27 "Margin" user)
		(31 "F.CrtYd" user "Package Geometry/Place Bound Top")
		(29 "B.CrtYd" user "Package Geometry/Place Bound Bottom")
		(35 "F.Fab" user "Ref Des/Assembly Top")
		(33 "B.Fab" user "Ref Des/Assembly Bottom")
	)
	(footprint ""
		(layer "B.Cu")
		(at 364.461806 -401.624546 180)
		(property "Reference" "R1095"
			(at 0 0 0)
			(layer "B.SilkS")
			(hide yes)
			(effects
				(font
					(size 1.27 1.27)
				)
				(justify mirror)
			)
		)
		(property "Value" ""
			(at 0 0 0)
			(layer "B.Fab")
			(effects
				(font
					(size 1.27 1.27)
				)
				(justify mirror)
			)
		)
		(duplicate_pad_numbers_are_jumpers no)
		(fp_line
			(start 1.2954 0.5842)
			(end 1.2954 -0.5842)
			(stroke
				(width 0.1524)
				(type default)
			)
			(layer "B.SilkS")
		)
		(fp_line
			(start 1.2954 -0.5842)
			(end -1.2954 -0.5842)
			(stroke
				(width 0.1524)
				(type default)
			)
			(layer "B.SilkS")
		)
		(fp_line
			(start -1.2954 0.5842)
			(end 1.2954 0.5842)
			(stroke
				(width 0.1524)
				(type default)
			)
			(layer "B.SilkS")
		)
		(fp_line
			(start -1.2954 -0.5842)
			(end -1.2954 0.5842)
			(stroke
				(width 0.1524)
				(type default)
			)
			(layer "B.SilkS")
		)
		(fp_line
			(start 1.1938 0.4064)
			(end 1.1938 -0.406654)
			(stroke
				(width 0.1)
				(type default)
			)
			(layer "B.Fab")
		)
		(fp_line
			(start 1.1938 -0.406654)
			(end 0.8636 -0.406654)
			(stroke
				(width 0.1)
				(type default)
			)
			(layer "B.Fab")
		)
		(fp_line
			(start 0.8636 0.4572)
			(end 0.8636 0.4318)
			(stroke
				(width 0.1)
				(type default)
			)
			(layer "B.Fab")
		)
		(fp_line
			(start 0.8636 0.4318)
			(end 0.8636 0.4064)
			(stroke
				(width 0.1)
				(type default)
			)
			(layer "B.Fab")
		)
		(fp_line
			(start 0.8636 0.4064)
			(end 1.1938 0.4064)
			(stroke
				(width 0.1)
				(type default)
			)
			(layer "B.Fab")
		)
		(fp_line
			(start 0.8636 -0.406654)
			(end 0.8636 -0.4572)
			(stroke
				(width 0.1)
				(type default)
			)
			(layer "B.Fab")
		)
		(fp_line
			(start 0.8636 -0.4572)
			(end -0.8636 -0.4572)
			(stroke
				(width 0.1)
				(type default)
			)
			(layer "B.Fab")
		)
		(fp_line
			(start -0.8636 0.4572)
			(end 0.8636 0.4572)
			(stroke
				(width 0.1)
				(type default)
			)
			(layer "B.Fab")
		)
		(fp_line
			(start -0.8636 0.4064)
			(end -0.8636 0.4572)
			(stroke
				(width 0.1)
				(type default)
			)
			(layer "B.Fab")
		)
		(fp_line
			(start -0.8636 -0.406654)
			(end -1.1938 -0.406654)
			(stroke
				(width 0.1)
				(type default)
			)
			(layer "B.Fab")
		)
		(fp_line
			(start -0.8636 -0.4572)
			(end -0.8636 -0.406654)
			(stroke
				(width 0.1)
				(type default)
			)
			(layer "B.Fab")
		)
		(fp_line
			(start -1.1938 0.4064)
			(end -0.8636 0.4064)
			(stroke
				(width 0.1)
				(type default)
			)
			(layer "B.Fab")
		)
		(fp_line
			(start -1.1938 -0.406654)
			(end -1.1938 0.4064)
			(stroke
				(width 0.1)
				(type default)
			)
			(layer "B.Fab")
		)
		(pad "1" smd rect
			(at 0.7366 0 90)
			(size 0.7112 0.8128)
			(layers "B.Cu" "B.Mask" "B.Paste")
			(net "P0V9_CPU0_RT3_2A_2D")
		)
		(pad "2" smd rect
			(at -0.7366 0 90)
			(size 0.7112 0.8128)
			(layers "B.Cu" "B.Mask" "B.Paste")
			(net "P0V9_CPU0_RT3_2A")
		)
	)
	(footprint ""
		(layer "B.Cu")
		(at 228.473508 -325.425562 180)
		(property "Reference" "C1087"
			(at 0 0 0)
			(layer "B.SilkS")
			(hide yes)
			(effects
				(font
					(size 1.27 1.27)
				)
				(justify mirror)
			)
		)
		(property "Value" ""
			(at 0 0 0)
			(layer "B.Fab")
			(effects
				(font
					(size 1.27 1.27)
				)
				(justify mirror)
			)
		)
		(duplicate_pad_numbers_are_jumpers no)
		(fp_line
			(start 0.7874 0.4064)
			(end 0.7874 -0.4064)
			(stroke
				(width 0.1524)
				(type default)
			)
			(layer "B.SilkS")
		)
		(fp_line
			(start 0.7874 -0.4064)
			(end -0.7874 -0.4064)
			(stroke
				(width 0.1524)
				(type default)
			)
			(layer "B.SilkS")
		)
		(fp_line
			(start -0.7874 0.4064)
			(end 0.7874 0.4064)
			(stroke
				(width 0.1524)
				(type default)
			)
			(layer "B.SilkS")
		)
		(fp_line
			(start -0.7874 -0.4064)
			(end -0.7874 0.4064)
			(stroke
				(width 0.1524)
				(type default)
			)
			(layer "B.SilkS")
		)
		(fp_line
			(start 0.67945 0.3048)
			(end 0.67945 -0.305054)
			(stroke
				(width 0.1)
				(type default)
			)
			(layer "B.Fab")
		)
		(fp_line
			(start 0.67945 -0.305054)
			(end 0.12065 -0.305054)
			(stroke
				(width 0.1)
				(type default)
			)
			(layer "B.Fab")
		)
		(fp_line
			(start 0.12065 0.3048)
			(end 0.67945 0.3048)
			(stroke
				(width 0.1)
				(type default)
			)
			(layer "B.Fab")
		)
		(fp_line
			(start 0.12065 0.2794)
			(end 0.12065 0.3048)
			(stroke
				(width 0.1)
				(type default)
			)
			(layer "B.Fab")
		)
		(fp_line
			(start 0.12065 -0.2794)
			(end -0.12065 -0.2794)
			(stroke
				(width 0.1)
				(type default)
			)
			(layer "B.Fab")
		)
		(fp_line
			(start 0.12065 -0.305054)
			(end 0.12065 -0.2794)
			(stroke
				(width 0.1)
				(type default)
			)
			(layer "B.Fab")
		)
		(fp_line
			(start -0.120396 0.3048)
			(end -0.120396 0.2794)
			(stroke
				(width 0.1)
				(type default)
			)
			(layer "B.Fab")
		)
		(fp_line
			(start -0.120396 0.2794)
			(end 0.12065 0.2794)
			(stroke
				(width 0.1)
				(type default)
			)
			(layer "B.Fab")
		)
		(fp_line
			(start -0.12065 -0.2794)
			(end -0.12065 -0.3048)
			(stroke
				(width 0.1)
				(type default)
			)
			(layer "B.Fab")
		)
		(fp_line
			(start -0.12065 -0.3048)
			(end -0.67945 -0.3048)
			(stroke
				(width 0.1)
				(type default)
			)
			(layer "B.Fab")
		)
		(fp_line
			(start -0.67945 0.3048)
			(end -0.120396 0.3048)
			(stroke
				(width 0.1)
				(type default)
			)
			(layer "B.Fab")
		)
		(fp_line
			(start -0.67945 -0.3048)
			(end -0.67945 0.3048)
			(stroke
				(width 0.1)
				(type default)
			)
			(layer "B.Fab")
		)
		(pad "1" smd circle
			(at 0.40005 0)
			(size 0 0)
			(layers "B.Cu" "B.Mask" "B.Paste")
			(net "P1V8_CPU0_RT_1D_ADC_TIC")
		)
		(pad "2" smd circle
			(at -0.40005 0)
			(size 0 0)
			(layers "B.Cu" "B.Mask" "B.Paste")
			(net "GND")
		)
	)
)
